(kicad_pcb
	(version 20260206)
	(generator "pcbnew")
	(generator_version "10.0")
	(general
		(thickness 1.6)
		(legacy_teardrops no)
	)
	(paper "A4")
	(title_block
		(title "01162023_DA0F0TEBIF0_F0T_Expander_BD_F_brd_V02_OCP.brd")
		(comment 1 "Grand Teton / footprints 3548-3551 of 9728")
	)
	(layers
		(0 "F.Cu" signal "TOP")
		(4 "In1.Cu" signal "GND")
		(6 "In2.Cu" signal "VCC")
		(8 "In3.Cu" signal "VCC1")
		(10 "In4.Cu" signal "GND1")
		(12 "In5.Cu" signal "IN1")
		(14 "In6.Cu" signal "GND2")
		(16 "In7.Cu" signal "IN2")
		(18 "In8.Cu" signal "GND3")
		(20 "In9.Cu" signal "IN3")
		(22 "In10.Cu" signal "GND4")
		(24 "In11.Cu" signal "IN4")
		(26 "In12.Cu" signal "GND5")
		(28 "In13.Cu" signal "IN5")
		(30 "In14.Cu" signal "GND6")
		(32 "In15.Cu" signal "IN6")
		(34 "In16.Cu" signal "GND7")
		(2 "B.Cu" signal "BOTTOM")
		(9 "F.Adhes" user "F.Adhesive")
		(11 "B.Adhes" user "B.Adhesive")
		(13 "F.Paste" user "Package Geometry/Pastemask Top")
		(15 "B.Paste" user "Package Geometry/Pastemask Bottom")
		(5 "F.SilkS" user "Ref Des/Silkscreen Top")
		(7 "B.SilkS" user "Ref Des/Silkscreen Bottom")
		(1 "F.Mask" user "Board Geometry/Soldermask Top")
		(3 "B.Mask" user "Board Geometry/Soldermask Bottom")
		(17 "Dwgs.User" user "User.Drawings")
		(19 "Cmts.User" user "User.Comments")
		(21 "Eco1.User" user "User.Eco1")
		(23 "Eco2.User" user "User.Eco2")
		(25 "Edge.Cuts" user "Board Geometry/Outline")
		(27 "Margin" user)
		(31 "F.CrtYd" user "Package Geometry/Place Bound Top")
		(29 "B.CrtYd" user "Package Geometry/Place Bound Bottom")
		(35 "F.Fab" user "Ref Des/Assembly Top")
		(33 "B.Fab" user "Ref Des/Assembly Bottom")
	)
	(footprint ""
		(layer "F.Cu")
		(at 233.594656 -204.44206 90)
		(property "Reference" "R5535"
			(at 0 0 90)
			(layer "F.SilkS")
			(hide yes)
			(effects
				(font
					(size 1.27 1.27)
				)
			)
		)
		(property "Value" ""
			(at 0 0 90)
			(layer "F.Fab")
			(effects
				(font
					(size 1.27 1.27)
				)
			)
		)
		(duplicate_pad_numbers_are_jumpers no)
		(fp_line
			(start 0.7874 -0.4064)
			(end 0.7874 0.4064)
			(stroke
				(width 0.1524)
				(type default)
			)
			(layer "F.SilkS")
		)
		(fp_line
			(start -0.7874 -0.4064)
			(end 0.7874 -0.4064)
			(stroke
				(width 0.1524)
				(type default)
			)
			(layer "F.SilkS")
		)
		(fp_line
			(start 0.7874 0.4064)
			(end -0.7874 0.4064)
			(stroke
				(width 0.1524)
				(type default)
			)
			(layer "F.SilkS")
		)
		(fp_line
			(start -0.7874 0.4064)
			(end -0.7874 -0.4064)
			(stroke
				(width 0.1524)
				(type default)
			)
			(layer "F.SilkS")
		)
		(fp_line
			(start -0.12065 -0.305054)
			(end -0.12065 -0.2794)
			(stroke
				(width 0.1)
				(type default)
			)
			(layer "F.Fab")
		)
		(fp_line
			(start -0.67945 -0.305054)
			(end -0.12065 -0.305054)
			(stroke
				(width 0.1)
				(type default)
			)
			(layer "F.Fab")
		)
		(fp_line
			(start 0.67945 -0.3048)
			(end 0.67945 0.3048)
			(stroke
				(width 0.1)
				(type default)
			)
			(layer "F.Fab")
		)
		(fp_line
			(start 0.12065 -0.3048)
			(end 0.67945 -0.3048)
			(stroke
				(width 0.1)
				(type default)
			)
			(layer "F.Fab")
		)
		(fp_line
			(start 0.12065 -0.2794)
			(end 0.12065 -0.3048)
			(stroke
				(width 0.1)
				(type default)
			)
			(layer "F.Fab")
		)
		(fp_line
			(start -0.12065 -0.2794)
			(end 0.12065 -0.2794)
			(stroke
				(width 0.1)
				(type default)
			)
			(layer "F.Fab")
		)
		(fp_line
			(start 0.120396 0.2794)
			(end -0.12065 0.2794)
			(stroke
				(width 0.1)
				(type default)
			)
			(layer "F.Fab")
		)
		(fp_line
			(start -0.12065 0.2794)
			(end -0.12065 0.3048)
			(stroke
				(width 0.1)
				(type default)
			)
			(layer "F.Fab")
		)
		(fp_line
			(start 0.67945 0.3048)
			(end 0.120396 0.3048)
			(stroke
				(width 0.1)
				(type default)
			)
			(layer "F.Fab")
		)
		(fp_line
			(start 0.120396 0.3048)
			(end 0.120396 0.2794)
			(stroke
				(width 0.1)
				(type default)
			)
			(layer "F.Fab")
		)
		(fp_line
			(start -0.12065 0.3048)
			(end -0.67945 0.3048)
			(stroke
				(width 0.1)
				(type default)
			)
			(layer "F.Fab")
		)
		(fp_line
			(start -0.67945 0.3048)
			(end -0.67945 -0.305054)
			(stroke
				(width 0.1)
				(type default)
			)
			(layer "F.Fab")
		)
		(pad "1" smd circle
			(at -0.40005 0 90)
			(size 0 0)
			(layers "F.Cu" "F.Mask" "F.Paste")
			(net "GND")
		)
		(pad "2" smd circle
			(at 0.40005 0 90)
			(size 0 0)
			(layers "F.Cu" "F.Mask" "F.Paste")
			(net "SPI_BIC1_MISO")
		)
	)
	(footprint ""
		(layer "F.Cu")
		(at 30.94736 -36.686998 90)
		(property "Reference" "C3661"
			(at 0 0 90)
			(layer "F.SilkS")
			(hide yes)
			(effects
				(font
					(size 1.27 1.27)
				)
			)
		)
		(property "Value" ""
			(at 0 0 90)
			(layer "F.Fab")
			(effects
				(font
					(size 1.27 1.27)
				)
			)
		)
		(duplicate_pad_numbers_are_jumpers no)
		(fp_line
			(start 0.7874 -0.4064)
			(end 0.7874 0.4064)
			(stroke
				(width 0.1524)
				(type default)
			)
			(layer "F.SilkS")
		)
		(fp_line
			(start -0.7874 -0.4064)
			(end 0.7874 -0.4064)
			(stroke
				(width 0.1524)
				(type default)
			)
			(layer "F.SilkS")
		)
		(fp_line
			(start 0.7874 0.4064)
			(end -0.7874 0.4064)
			(stroke
				(width 0.1524)
				(type default)
			)
			(layer "F.SilkS")
		)
		(fp_line
			(start -0.7874 0.4064)
			(end -0.7874 -0.4064)
			(stroke
				(width 0.1524)
				(type default)
			)
			(layer "F.SilkS")
		)
		(fp_line
			(start -0.12065 -0.305054)
			(end -0.12065 -0.2794)
			(stroke
				(width 0.1)
				(type default)
			)
			(layer "F.Fab")
		)
		(fp_line
			(start -0.67945 -0.305054)
			(end -0.12065 -0.305054)
			(stroke
				(width 0.1)
				(type default)
			)
			(layer "F.Fab")
		)
		(fp_line
			(start 0.67945 -0.3048)
			(end 0.67945 0.3048)
			(stroke
				(width 0.1)
				(type default)
			)
			(layer "F.Fab")
		)
		(fp_line
			(start 0.12065 -0.3048)
			(end 0.67945 -0.3048)
			(stroke
				(width 0.1)
				(type default)
			)
			(layer "F.Fab")
		)
		(fp_line
			(start 0.12065 -0.2794)
			(end 0.12065 -0.3048)
			(stroke
				(width 0.1)
				(type default)
			)
			(layer "F.Fab")
		)
		(fp_line
			(start -0.12065 -0.2794)
			(end 0.12065 -0.2794)
			(stroke
				(width 0.1)
				(type default)
			)
			(layer "F.Fab")
		)
		(fp_line
			(start 0.120396 0.2794)
			(end -0.12065 0.2794)
			(stroke
				(width 0.1)
				(type default)
			)
			(layer "F.Fab")
		)
		(fp_line
			(start -0.12065 0.2794)
			(end -0.12065 0.3048)
			(stroke
				(width 0.1)
				(type default)
			)
			(layer "F.Fab")
		)
		(fp_line
			(start 0.67945 0.3048)
			(end 0.120396 0.3048)
			(stroke
				(width 0.1)
				(type default)
			)
			(layer "F.Fab")
		)
		(fp_line
			(start 0.120396 0.3048)
			(end 0.120396 0.2794)
			(stroke
				(width 0.1)
				(type default)
			)
			(layer "F.Fab")
		)
		(fp_line
			(start -0.12065 0.3048)
			(end -0.67945 0.3048)
			(stroke
				(width 0.1)
				(type default)
			)
			(layer "F.Fab")
		)
		(fp_line
			(start -0.67945 0.3048)
			(end -0.67945 -0.305054)
			(stroke
				(width 0.1)
				(type default)
			)
			(layer "F.Fab")
		)
		(pad "1" smd circle
			(at -0.40005 0 90)
			(size 0 0)
			(layers "F.Cu" "F.Mask" "F.Paste")
			(net "P3V3_AUX")
		)
		(pad "2" smd circle
			(at 0.40005 0 90)
			(size 0 0)
			(layers "F.Cu" "F.Mask" "F.Paste")
			(net "GND")
		)
	)
	(footprint ""
		(layer "F.Cu")
		(at 12.494768 -157.304994 -90)
		(property "Reference" "PU71"
			(at -3.272536 -1.526032 0)
			(unlocked yes)
			(layer "F.SilkS")
			(effects
				(font
					(size 0.7874 0.5842)
					(thickness 0.1524)
				)
				(justify left)
			)
		)
		(property "Value" ""
			(at 0 0 270)
			(layer "F.Fab")
			(effects
				(font
					(size 1.27 1.27)
				)
			)
		)
		(duplicate_pad_numbers_are_jumpers no)
		(fp_line
			(start -1.549908 2.549906)
			(end -0.753872 2.549906)
			(stroke
				(width 0.1524)
				(type default)
			)
			(layer "F.SilkS")
		)
		(fp_line
			(start -0.245872 2.549906)
			(end 0.245872 2.549906)
			(stroke
				(width 0.1524)
				(type default)
			)
			(layer "F.SilkS")
		)
		(fp_line
			(start 0.753872 2.549906)
			(end 1.549908 2.549906)
			(stroke
				(width 0.1524)
				(type default)
			)
			(layer "F.SilkS")
		)
		(fp_line
			(start 1.549908 2.549906)
			(end 1.549908 2.253996)
			(stroke
				(width 0.1524)
				(type default)
			)
			(layer "F.SilkS")
		)
		(fp_line
			(start -1.549908 2.253996)
			(end -1.549908 2.549906)
			(stroke
				(width 0.1524)
				(type default)
			)
			(layer "F.SilkS")
		)
		(fp_line
			(start 1.549908 -2.253996)
			(end 1.549908 -2.549906)
			(stroke
				(width 0.1524)
				(type default)
			)
			(layer "F.SilkS")
		)
		(fp_line
			(start -1.549908 -2.549906)
			(end -1.549908 -2.251964)
			(stroke
				(width 0.1524)
				(type default)
			)
			(layer "F.SilkS")
		)
		(fp_line
			(start -0.752094 -2.549906)
			(end -1.549908 -2.549906)
			(stroke
				(width 0.1524)
				(type default)
			)
			(layer "F.SilkS")
		)
		(fp_line
			(start 0.2413 -2.549906)
			(end -0.2413 -2.549906)
			(stroke
				(width 0.1524)
				(type default)
			)
			(layer "F.SilkS")
		)
		(fp_line
			(start 1.549908 -2.549906)
			(end 0.752094 -2.549906)
			(stroke
				(width 0.1524)
				(type default)
			)
			(layer "F.SilkS")
		)
		(fp_poly
			(pts
				(xy -1.702054 -2.417064) (xy -2.605278 -2.718054) (xy -2.003298 -3.320288)
			)
			(stroke
				(width 0)
				(type default)
			)
			(fill yes)
			(layer "F.SilkS")
		)
		(fp_line
			(start -1.549908 2.549906)
			(end 1.549908 2.549906)
			(stroke
				(width 0.1)
				(type default)
			)
			(layer "F.Fab")
		)
		(fp_line
			(start 1.549908 2.549906)
			(end 1.549908 -2.549906)
			(stroke
				(width 0.1)
				(type default)
			)
			(layer "F.Fab")
		)
		(fp_line
			(start -1.549908 -2.549906)
			(end -1.549908 2.549906)
			(stroke
				(width 0.1)
				(type default)
			)
			(layer "F.Fab")
		)
		(fp_line
			(start 1.549908 -2.549906)
			(end -1.549908 -2.549906)
			(stroke
				(width 0.1)
				(type default)
			)
			(layer "F.Fab")
		)
		(fp_poly
			(pts
				(xy -1.891538 -1.999996) (xy -2.7432 -1.574292) (xy -2.7432 -2.4257)
			)
			(stroke
				(width 0)
				(type default)
			)
			(fill yes)
			(layer "F.Fab")
		)
		(fp_text user "10"
			(at -1.4224 3.044444 270)
			(unlocked yes)
			(layer "F.SilkS")
			(effects
				(font
					(size 0.635 0.4064)
					(thickness 0.1524)
				)
			)
		)
		(fp_text user "11"
			(at 1.182878 2.989072 270)
			(unlocked yes)
			(layer "F.SilkS")
			(effects
				(font
					(size 0.635 0.4064)
					(thickness 0.1524)
				)
			)
		)
		(fp_text user "9"
			(at -2.338832 2.5908 180)
			(unlocked yes)
			(layer "F.SilkS")
			(effects
				(font
					(size 0.635 0.4064)
					(thickness 0.1524)
				)
			)
		)
		(fp_text user "12"
			(at 2.482088 1.070864 180)
			(unlocked yes)
			(layer "F.SilkS")
			(effects
				(font
					(size 0.635 0.4064)
					(thickness 0.1524)
				)
			)
		)
		(fp_text user "21_22"
			(at 0.395986 -3.379724 270)
			(unlocked yes)
			(layer "F.SilkS")
			(effects
				(font
					(size 0.635 0.4064)
					(thickness 0.1524)
				)
			)
		)
		(fp_text user "20"
			(at 2.143252 -3.877564 180)
			(unlocked yes)
			(layer "F.SilkS")
			(effects
				(font
					(size 0.635 0.4064)
					(thickness 0.1524)
				)
			)
		)
		(fp_text user "11"
			(at 1.1938 3.329432 270)
			(unlocked yes)
			(layer "F.Fab")
			(effects
				(font
					(size 0.635 0.4064)
					(thickness 0.1524)
				)
			)
		)
		(fp_text user "10"
			(at -1.4224 3.253232 270)
			(unlocked yes)
			(layer "F.Fab")
			(effects
				(font
					(size 0.635 0.4064)
					(thickness 0.1524)
				)
			)
		)
		(fp_text user "12"
			(at 2.207768 2.7178 180)
			(unlocked yes)
			(layer "F.Fab")
			(effects
				(font
					(size 0.635 0.4064)
					(thickness 0.1524)
				)
			)
		)
		(fp_text user "9"
			(at -2.338832 2.5908 180)
			(unlocked yes)
			(layer "F.Fab")
			(effects
				(font
					(size 0.635 0.4064)
					(thickness 0.1524)
				)
			)
		)
		(fp_text user "20"
			(at 2.055368 -2.7686 180)
			(unlocked yes)
			(layer "F.Fab")
			(effects
				(font
					(size 0.635 0.4064)
					(thickness 0.1524)
				)
			)
		)
		(fp_text user "21_22"
			(at -0.0762 -3.401568 270)
			(unlocked yes)
			(layer "F.Fab")
			(effects
				(font
					(size 0.635 0.4064)
					(thickness 0.1524)
				)
			)
		)
		(pad "1" smd circle
			(at -1.374902 -1.999996 180)
			(size 0 0)
			(layers "F.Cu" "F.Mask" "F.Paste")
			(net "P12V_NIC0_CO_EN")
		)
		(pad "2" smd rect
			(at -1.400048 -1.500124 180)
			(size 0.254 0.8128)
			(layers "F.Cu" "F.Mask" "F.Paste")
			(net "GND")
		)
		(pad "3" smd rect
			(at -1.400048 -0.999998 180)
			(size 0.254 0.8128)
			(layers "F.Cu" "F.Mask" "F.Paste")
			(net "GND")
		)
		(pad "4" smd rect
			(at -1.400048 -0.499872 180)
			(size 0.254 0.8128)
			(layers "F.Cu" "F.Mask" "F.Paste")
			(net "P12V_NIC0_CO_TIMER")
		)
		(pad "5" smd rect
			(at -1.400048 0 180)
			(size 0.254 0.8128)
			(layers "F.Cu" "F.Mask" "F.Paste")
			(net "P12V_NIC0_CO_ISET")
		)
		(pad "6" smd rect
			(at -1.400048 0.499872 180)
			(size 0.254 0.8128)
			(layers "F.Cu" "F.Mask" "F.Paste")
			(net "P12V_NIC0_CO_SS")
		)
		(pad "7" smd rect
			(at -1.400048 0.999998 180)
			(size 0.254 0.8128)
			(layers "F.Cu" "F.Mask" "F.Paste")
			(net "GND")
		)
		(pad "8" smd rect
			(at -1.400048 1.500124 180)
			(size 0.254 0.8128)
			(layers "F.Cu" "F.Mask" "F.Paste")
			(net "P12V_NIC0_CO_IMON_VR")
		)
		(pad "9" smd rect
			(at -1.400048 1.999996 180)
			(size 0.254 0.8128)
			(layers "F.Cu" "F.Mask" "F.Paste")
			(net "P12V_NIC0_CO_FLTB")
		)
		(pad "10" smd rect
			(at -0.499872 2.400046 270)
			(size 0.254 0.8128)
			(layers "F.Cu" "F.Mask" "F.Paste")
			(net "PWRGD_P12V_NIC0_CO")
		)
		(pad "11" smd rect
			(at 0.499872 2.400046 270)
			(size 0.254 0.8128)
			(layers "F.Cu" "F.Mask" "F.Paste")
			(net "P12V_NIC0_CO_OV_FB")
		)
		(pad "12" smd rect
			(at 1.400048 1.999996 180)
			(size 0.254 0.8128)
			(layers "F.Cu" "F.Mask" "F.Paste")
			(net "P12V_NIC0_CO_AVIN_PD")
		)
		(pad "13" smd rect
			(at 1.400048 1.500124 180)
			(size 0.254 0.8128)
			(layers "F.Cu" "F.Mask" "F.Paste")
			(net "P12V_NIC0_R")
		)
		(pad "14" smd rect
			(at 1.400048 0.999998 180)
			(size 0.254 0.8128)
			(layers "F.Cu" "F.Mask" "F.Paste")
			(net "P12V_NIC0_R")
		)
		(pad "15" smd rect
			(at 1.400048 0.499872 180)
			(size 0.254 0.8128)
			(layers "F.Cu" "F.Mask" "F.Paste")
			(net "P12V_NIC0_R")
		)
		(pad "16" smd rect
			(at 1.400048 0 180)
			(size 0.254 0.8128)
			(layers "F.Cu" "F.Mask" "F.Paste")
			(net "P12V_NIC0_R")
		)
		(pad "17" smd rect
			(at 1.400048 -0.499872 180)
			(size 0.254 0.8128)
			(layers "F.Cu" "F.Mask" "F.Paste")
			(net "P12V_NIC0_R")
		)
		(pad "18" smd rect
			(at 1.400048 -0.999998 180)
			(size 0.254 0.8128)
			(layers "F.Cu" "F.Mask" "F.Paste")
			(net "P12V_NIC0_R")
		)
		(pad "19" smd rect
			(at 1.400048 -1.500124 180)
			(size 0.254 0.8128)
			(layers "F.Cu" "F.Mask" "F.Paste")
			(net "P12V_NIC0_R")
		)
		(pad "20" smd rect
			(at 1.400048 -1.999996 180)
			(size 0.254 0.8128)
			(layers "F.Cu" "F.Mask" "F.Paste")
			(net "P12V_NIC0_R")
		)
		(pad "21_22" smd circle
			(at 0.499872 -2.337562 180)
			(size 0 0)
			(layers "F.Cu" "F.Mask" "F.Paste")
			(net "P12V_AUX")
		)
		(pad "23" smd rect
			(at 0 -1.100074 180)
			(size 0.254 1.27)
			(layers "F.Cu" "F.Mask" "F.Paste")
			(net "P12V_AUX")
		)
		(pad "24" smd rect
			(at 0 -0.199898 180)
			(size 0.254 1.27)
			(layers "F.Cu" "F.Mask" "F.Paste")
			(net "P12V_AUX")
		)
		(pad "25" smd rect
			(at 0 0.700024 180)
			(size 0.254 1.27)
			(layers "F.Cu" "F.Mask" "F.Paste")
			(net "P12V_AUX")
		)
		(pad "26" smd rect
			(at 0 1.599946 180)
			(size 0.254 1.27)
			(layers "F.Cu" "F.Mask" "F.Paste")
			(net "P12V_AUX")
		)
	)
	(footprint ""
		(layer "F.Cu")
		(at 431.247296 -36.686998 90)
		(property "Reference" "C3673"
			(at 0 0 90)
			(layer "F.SilkS")
			(hide yes)
			(effects
				(font
					(size 1.27 1.27)
				)
			)
		)
		(property "Value" ""
			(at 0 0 90)
			(layer "F.Fab")
			(effects
				(font
					(size 1.27 1.27)
				)
			)
		)
		(duplicate_pad_numbers_are_jumpers no)
		(fp_line
			(start 0.7874 -0.4064)
			(end 0.7874 0.4064)
			(stroke
				(width 0.1524)
				(type default)
			)
			(layer "F.SilkS")
		)
		(fp_line
			(start -0.7874 -0.4064)
			(end 0.7874 -0.4064)
			(stroke
				(width 0.1524)
				(type default)
			)
			(layer "F.SilkS")
		)
		(fp_line
			(start 0.7874 0.4064)
			(end -0.7874 0.4064)
			(stroke
				(width 0.1524)
				(type default)
			)
			(layer "F.SilkS")
		)
		(fp_line
			(start -0.7874 0.4064)
			(end -0.7874 -0.4064)
			(stroke
				(width 0.1524)
				(type default)
			)
			(layer "F.SilkS")
		)
		(fp_line
			(start -0.12065 -0.305054)
			(end -0.12065 -0.2794)
			(stroke
				(width 0.1)
				(type default)
			)
			(layer "F.Fab")
		)
		(fp_line
			(start -0.67945 -0.305054)
			(end -0.12065 -0.305054)
			(stroke
				(width 0.1)
				(type default)
			)
			(layer "F.Fab")
		)
		(fp_line
			(start 0.67945 -0.3048)
			(end 0.67945 0.3048)
			(stroke
				(width 0.1)
				(type default)
			)
			(layer "F.Fab")
		)
		(fp_line
			(start 0.12065 -0.3048)
			(end 0.67945 -0.3048)
			(stroke
				(width 0.1)
				(type default)
			)
			(layer "F.Fab")
		)
		(fp_line
			(start 0.12065 -0.2794)
			(end 0.12065 -0.3048)
			(stroke
				(width 0.1)
				(type default)
			)
			(layer "F.Fab")
		)
		(fp_line
			(start -0.12065 -0.2794)
			(end 0.12065 -0.2794)
			(stroke
				(width 0.1)
				(type default)
			)
			(layer "F.Fab")
		)
		(fp_line
			(start 0.120396 0.2794)
			(end -0.12065 0.2794)
			(stroke
				(width 0.1)
				(type default)
			)
			(layer "F.Fab")
		)
		(fp_line
			(start -0.12065 0.2794)
			(end -0.12065 0.3048)
			(stroke
				(width 0.1)
				(type default)
			)
			(layer "F.Fab")
		)
		(fp_line
			(start 0.67945 0.3048)
			(end 0.120396 0.3048)
			(stroke
				(width 0.1)
				(type default)
			)
			(layer "F.Fab")
		)
		(fp_line
			(start 0.120396 0.3048)
			(end 0.120396 0.2794)
			(stroke
				(width 0.1)
				(type default)
			)
			(layer "F.Fab")
		)
		(fp_line
			(start -0.12065 0.3048)
			(end -0.67945 0.3048)
			(stroke
				(width 0.1)
				(type default)
			)
			(layer "F.Fab")
		)
		(fp_line
			(start -0.67945 0.3048)
			(end -0.67945 -0.305054)
			(stroke
				(width 0.1)
				(type default)
			)
			(layer "F.Fab")
		)
		(pad "1" smd circle
			(at -0.40005 0 90)
			(size 0 0)
			(layers "F.Cu" "F.Mask" "F.Paste")
			(net "P3V3_AUX")
		)
		(pad "2" smd circle
			(at 0.40005 0 90)
			(size 0 0)
			(layers "F.Cu" "F.Mask" "F.Paste")
			(net "GND")
		)
	)
)
